# S9S_MB_2U (Grand Teton) — schematic netlist excerpt (pin names and nets, part order shuffled) for the footprints in the layout excerpt that follows; sources: Cadence DE-HDL packaged netlist, KiCad conversion of 03242023_DA0F0TMBIJ0_F0T_Motherboard_J_brd_V01_OCP.brd

R1339  Q_RES  10K 1% CHIP  pkg 0402LF  page 201 : A = P3V3_AUX ; B = FM_BIOS_IMAGE_SWAP_N
C62  Q_CAP  2.2UF 6.3V 20% X6S  pkg C0402  page 102 : A = P3V3_AUX ; B = GND

(kicad_pcb
	(version 20260206)
	(generator "pcbnew")
	(generator_version "10.0")
	(general
		(thickness 1.6)
		(legacy_teardrops no)
	)
	(paper "A4")
	(title_block
		(title "03242023_DA0F0TMBIJ0_F0T_Motherboard_J_brd_V01_OCP.brd")
		(comment 1 "Grand Teton / footprints 5844-5845 of 6105")
	)
	(layers
		(0 "F.Cu" signal "TOP")
		(4 "In1.Cu" signal "GND")
		(6 "In2.Cu" signal "IN1")
		(8 "In3.Cu" signal "GND1")
		(10 "In4.Cu" signal "IN2")
		(12 "In5.Cu" signal "GND2")
		(14 "In6.Cu" signal "IN3")
		(16 "In7.Cu" signal "GND3")
		(18 "In8.Cu" signal "VCC")
		(20 "In9.Cu" signal "VCC1")
		(22 "In10.Cu" signal "GND4")
		(24 "In11.Cu" signal "IN4")
		(26 "In12.Cu" signal "GND5")
		(28 "In13.Cu" signal "IN5")
		(30 "In14.Cu" signal "GND6")
		(32 "In15.Cu" signal "IN6")
		(34 "In16.Cu" signal "GND7")
		(2 "B.Cu" signal "BOTTOM")
		(9 "F.Adhes" user "F.Adhesive")
		(11 "B.Adhes" user "B.Adhesive")
		(13 "F.Paste" user "Package Geometry/Pastemask Top")
		(15 "B.Paste" user "Package Geometry/Pastemask Bottom")
		(5 "F.SilkS" user "Ref Des/Silkscreen Top")
		(7 "B.SilkS" user "Ref Des/Silkscreen Bottom")
		(1 "F.Mask" user "Board Geometry/Soldermask Top")
		(3 "B.Mask" user "Board Geometry/Soldermask Bottom")
		(17 "Dwgs.User" user "User.Drawings")
		(19 "Cmts.User" user "User.Comments")
		(21 "Eco1.User" user "User.Eco1")
		(23 "Eco2.User" user "User.Eco2")
		(25 "Edge.Cuts" user "Board Geometry/Outline")
		(27 "Margin" user)
		(31 "F.CrtYd" user "Package Geometry/Place Bound Top")
		(29 "B.CrtYd" user "Package Geometry/Place Bound Bottom")
		(35 "F.Fab" user "Ref Des/Assembly Top")
		(33 "B.Fab" user "Ref Des/Assembly Bottom")
	)
	(footprint ""
		(layer "B.Cu")
		(at 23.240746 -319.268856 180)
		(property "Reference" "C62"
			(at 0 0 0)
			(layer "B.SilkS")
			(hide yes)
			(effects
				(font
					(size 1.27 1.27)
				)
				(justify mirror)
			)
		)
		(property "Value" ""
			(at 0 0 0)
			(layer "B.Fab")
			(effects
				(font
					(size 1.27 1.27)
				)
				(justify mirror)
			)
		)
		(duplicate_pad_numbers_are_jumpers no)
		(fp_line
			(start 0.7874 0.4064)
			(end 0.7874 -0.4064)
			(stroke
				(width 0.1524)
				(type default)
			)
			(layer "B.SilkS")
		)
		(fp_line
			(start 0.7874 -0.4064)
			(end -0.7874 -0.4064)
			(stroke
				(width 0.1524)
				(type default)
			)
			(layer "B.SilkS")
		)
		(fp_line
			(start -0.7874 0.4064)
			(end 0.7874 0.4064)
			(stroke
				(width 0.1524)
				(type default)
			)
			(layer "B.SilkS")
		)
		(fp_line
			(start -0.7874 -0.4064)
			(end -0.7874 0.4064)
			(stroke
				(width 0.1524)
				(type default)
			)
			(layer "B.SilkS")
		)
		(fp_line
			(start 0.67945 0.3048)
			(end 0.67945 -0.305054)
			(stroke
				(width 0.1)
				(type default)
			)
			(layer "B.Fab")
		)
		(fp_line
			(start 0.67945 -0.305054)
			(end 0.12065 -0.305054)
			(stroke
				(width 0.1)
				(type default)
			)
			(layer "B.Fab")
		)
		(fp_line
			(start 0.12065 0.3048)
			(end 0.67945 0.3048)
			(stroke
				(width 0.1)
				(type default)
			)
			(layer "B.Fab")
		)
		(fp_line
			(start 0.12065 0.2794)
			(end 0.12065 0.3048)
			(stroke
				(width 0.1)
				(type default)
			)
			(layer "B.Fab")
		)
		(fp_line
			(start 0.12065 -0.2794)
			(end -0.12065 -0.2794)
			(stroke
				(width 0.1)
				(type default)
			)
			(layer "B.Fab")
		)
		(fp_line
			(start 0.12065 -0.305054)
			(end 0.12065 -0.2794)
			(stroke
				(width 0.1)
				(type default)
			)
			(layer "B.Fab")
		)
		(fp_line
			(start -0.120396 0.3048)
			(end -0.120396 0.2794)
			(stroke
				(width 0.1)
				(type default)
			)
			(layer "B.Fab")
		)
		(fp_line
			(start -0.120396 0.2794)
			(end 0.12065 0.2794)
			(stroke
				(width 0.1)
				(type default)
			)
			(layer "B.Fab")
		)
		(fp_line
			(start -0.12065 -0.2794)
			(end -0.12065 -0.3048)
			(stroke
				(width 0.1)
				(type default)
			)
			(layer "B.Fab")
		)
		(fp_line
			(start -0.12065 -0.3048)
			(end -0.67945 -0.3048)
			(stroke
				(width 0.1)
				(type default)
			)
			(layer "B.Fab")
		)
		(fp_line
			(start -0.67945 0.3048)
			(end -0.120396 0.3048)
			(stroke
				(width 0.1)
				(type default)
			)
			(layer "B.Fab")
		)
		(fp_line
			(start -0.67945 -0.3048)
			(end -0.67945 0.3048)
			(stroke
				(width 0.1)
				(type default)
			)
			(layer "B.Fab")
		)
		(pad "1" smd circle
			(at 0.40005 0)
			(size 0 0)
			(layers "B.Cu" "B.Mask" "B.Paste")
			(net "P3V3_AUX")
		)
		(pad "2" smd circle
			(at -0.40005 0)
			(size 0 0)
			(layers "B.Cu" "B.Mask" "B.Paste")
			(net "GND")
		)
	)
	(footprint ""
		(layer "B.Cu")
		(at 315.110622 -51.171348)
		(property "Reference" "R1339"
			(at 0 0 0)
			(layer "B.SilkS")
			(hide yes)
			(effects
				(font
					(size 1.27 1.27)
				)
				(justify mirror)
			)
		)
		(property "Value" ""
			(at 0 0 0)
			(layer "B.Fab")
			(effects
				(font
					(size 1.27 1.27)
				)
				(justify mirror)
			)
		)
		(duplicate_pad_numbers_are_jumpers no)
		(fp_line
			(start -0.7874 -0.4064)
			(end -0.7874 0.4064)
			(stroke
				(width 0.1524)
				(type default)
			)
			(layer "B.SilkS")
		)
		(fp_line
			(start -0.7874 0.4064)
			(end 0.7874 0.4064)
			(stroke
				(width 0.1524)
				(type default)
			)
			(layer "B.SilkS")
		)
		(fp_line
			(start 0.7874 -0.4064)
			(end -0.7874 -0.4064)
			(stroke
				(width 0.1524)
				(type default)
			)
			(layer "B.SilkS")
		)
		(fp_line
			(start 0.7874 0.4064)
			(end 0.7874 -0.4064)
			(stroke
				(width 0.1524)
				(type default)
			)
			(layer "B.SilkS")
		)
		(fp_line
			(start -0.67945 -0.3048)
			(end -0.67945 0.3048)
			(stroke
				(width 0.1)
				(type default)
			)
			(layer "B.Fab")
		)
		(fp_line
			(start -0.67945 0.3048)
			(end -0.120396 0.3048)
			(stroke
				(width 0.1)
				(type default)
			)
			(layer "B.Fab")
		)
		(fp_line
			(start -0.12065 -0.3048)
			(end -0.67945 -0.3048)
			(stroke
				(width 0.1)
				(type default)
			)
			(layer "B.Fab")
		)
		(fp_line
			(start -0.12065 -0.2794)
			(end -0.12065 -0.3048)
			(stroke
				(width 0.1)
				(type default)
			)
			(layer "B.Fab")
		)
		(fp_line
			(start -0.120396 0.2794)
			(end 0.12065 0.2794)
			(stroke
				(width 0.1)
				(type default)
			)
			(layer "B.Fab")
		)
		(fp_line
			(start -0.120396 0.3048)
			(end -0.120396 0.2794)
			(stroke
				(width 0.1)
				(type default)
			)
			(layer "B.Fab")
		)
		(fp_line
			(start 0.12065 -0.305054)
			(end 0.12065 -0.2794)
			(stroke
				(width 0.1)
				(type default)
			)
			(layer "B.Fab")
		)
		(fp_line
			(start 0.12065 -0.2794)
			(end -0.12065 -0.2794)
			(stroke
				(width 0.1)
				(type default)
			)
			(layer "B.Fab")
		)
		(fp_line
			(start 0.12065 0.2794)
			(end 0.12065 0.3048)
			(stroke
				(width 0.1)
				(type default)
			)
			(layer "B.Fab")
		)
		(fp_line
			(start 0.12065 0.3048)
			(end 0.67945 0.3048)
			(stroke
				(width 0.1)
				(type default)
			)
			(layer "B.Fab")
		)
		(fp_line
			(start 0.67945 -0.305054)
			(end 0.12065 -0.305054)
			(stroke
				(width 0.1)
				(type default)
			)
			(layer "B.Fab")
		)
		(fp_line
			(start 0.67945 0.3048)
			(end 0.67945 -0.305054)
			(stroke
				(width 0.1)
				(type default)
			)
			(layer "B.Fab")
		)
		(pad "1" smd circle
			(at 0.40005 0 180)
			(size 0 0)
			(layers "B.Cu" "B.Mask" "B.Paste")
			(net "P3V3_AUX")
		)
		(pad "2" smd circle
			(at -0.40005 0 180)
			(size 0 0)
			(layers "B.Cu" "B.Mask" "B.Paste")
			(net "FM_BIOS_IMAGE_SWAP_N")
		)
	)
)
